(kicad_pcb
	(version 20260206)
	(generator "pcbnew")
	(generator_version "10.0")
	(general
		(thickness 1.6)
		(legacy_teardrops no)
	)
	(paper "A4")
	(title_block
		(title "03242023_DA0F0TMBIJ0_F0T_Motherboard_J_brd_V01_OCP.brd")
		(comment 1 "Grand Teton / footprints 1697-1700 of 6105")
	)
	(layers
		(0 "F.Cu" signal "TOP")
		(4 "In1.Cu" signal "GND")
		(6 "In2.Cu" signal "IN1")
		(8 "In3.Cu" signal "GND1")
		(10 "In4.Cu" signal "IN2")
		(12 "In5.Cu" signal "GND2")
		(14 "In6.Cu" signal "IN3")
		(16 "In7.Cu" signal "GND3")
		(18 "In8.Cu" signal "VCC")
		(20 "In9.Cu" signal "VCC1")
		(22 "In10.Cu" signal "GND4")
		(24 "In11.Cu" signal "IN4")
		(26 "In12.Cu" signal "GND5")
		(28 "In13.Cu" signal "IN5")
		(30 "In14.Cu" signal "GND6")
		(32 "In15.Cu" signal "IN6")
		(34 "In16.Cu" signal "GND7")
		(2 "B.Cu" signal "BOTTOM")
		(9 "F.Adhes" user "F.Adhesive")
		(11 "B.Adhes" user "B.Adhesive")
		(13 "F.Paste" user "Package Geometry/Pastemask Top")
		(15 "B.Paste" user "Package Geometry/Pastemask Bottom")
		(5 "F.SilkS" user "Ref Des/Silkscreen Top")
		(7 "B.SilkS" user "Ref Des/Silkscreen Bottom")
		(1 "F.Mask" user "Board Geometry/Soldermask Top")
		(3 "B.Mask" user "Board Geometry/Soldermask Bottom")
		(17 "Dwgs.User" user "User.Drawings")
		(19 "Cmts.User" user "User.Comments")
		(21 "Eco1.User" user "User.Eco1")
		(23 "Eco2.User" user "User.Eco2")
		(25 "Edge.Cuts" user "Board Geometry/Outline")
		(27 "Margin" user)
		(31 "F.CrtYd" user "Package Geometry/Place Bound Top")
		(29 "B.CrtYd" user "Package Geometry/Place Bound Bottom")
		(35 "F.Fab" user "Ref Des/Assembly Top")
		(33 "B.Fab" user "Ref Des/Assembly Bottom")
	)
	(footprint ""
		(layer "F.Cu")
		(at 367.44783 -251.375418 90)
		(property "Reference" "C1044"
			(at 0 0 90)
			(layer "F.SilkS")
			(hide yes)
			(effects
				(font
					(size 1.27 1.27)
				)
			)
		)
		(property "Value" ""
			(at 0 0 90)
			(layer "F.Fab")
			(effects
				(font
					(size 1.27 1.27)
				)
			)
		)
		(duplicate_pad_numbers_are_jumpers no)
		(fp_line
			(start 0.7874 -0.4064)
			(end 0.7874 0.4064)
			(stroke
				(width 0.1524)
				(type default)
			)
			(layer "F.SilkS")
		)
		(fp_line
			(start -0.7874 -0.4064)
			(end 0.7874 -0.4064)
			(stroke
				(width 0.1524)
				(type default)
			)
			(layer "F.SilkS")
		)
		(fp_line
			(start 0.7874 0.4064)
			(end -0.7874 0.4064)
			(stroke
				(width 0.1524)
				(type default)
			)
			(layer "F.SilkS")
		)
		(fp_line
			(start -0.7874 0.4064)
			(end -0.7874 -0.4064)
			(stroke
				(width 0.1524)
				(type default)
			)
			(layer "F.SilkS")
		)
		(fp_line
			(start -0.12065 -0.305054)
			(end -0.12065 -0.2794)
			(stroke
				(width 0.1)
				(type default)
			)
			(layer "F.Fab")
		)
		(fp_line
			(start -0.67945 -0.305054)
			(end -0.12065 -0.305054)
			(stroke
				(width 0.1)
				(type default)
			)
			(layer "F.Fab")
		)
		(fp_line
			(start 0.67945 -0.3048)
			(end 0.67945 0.3048)
			(stroke
				(width 0.1)
				(type default)
			)
			(layer "F.Fab")
		)
		(fp_line
			(start 0.12065 -0.3048)
			(end 0.67945 -0.3048)
			(stroke
				(width 0.1)
				(type default)
			)
			(layer "F.Fab")
		)
		(fp_line
			(start 0.12065 -0.2794)
			(end 0.12065 -0.3048)
			(stroke
				(width 0.1)
				(type default)
			)
			(layer "F.Fab")
		)
		(fp_line
			(start -0.12065 -0.2794)
			(end 0.12065 -0.2794)
			(stroke
				(width 0.1)
				(type default)
			)
			(layer "F.Fab")
		)
		(fp_line
			(start 0.120396 0.2794)
			(end -0.12065 0.2794)
			(stroke
				(width 0.1)
				(type default)
			)
			(layer "F.Fab")
		)
		(fp_line
			(start -0.12065 0.2794)
			(end -0.12065 0.3048)
			(stroke
				(width 0.1)
				(type default)
			)
			(layer "F.Fab")
		)
		(fp_line
			(start 0.67945 0.3048)
			(end 0.120396 0.3048)
			(stroke
				(width 0.1)
				(type default)
			)
			(layer "F.Fab")
		)
		(fp_line
			(start 0.120396 0.3048)
			(end 0.120396 0.2794)
			(stroke
				(width 0.1)
				(type default)
			)
			(layer "F.Fab")
		)
		(fp_line
			(start -0.12065 0.3048)
			(end -0.67945 0.3048)
			(stroke
				(width 0.1)
				(type default)
			)
			(layer "F.Fab")
		)
		(fp_line
			(start -0.67945 0.3048)
			(end -0.67945 -0.305054)
			(stroke
				(width 0.1)
				(type default)
			)
			(layer "F.Fab")
		)
		(pad "1" smd circle
			(at -0.40005 0 90)
			(size 0 0)
			(layers "F.Cu" "F.Mask" "F.Paste")
			(net "PVCCIN_CPU0")
		)
		(pad "2" smd circle
			(at 0.40005 0 90)
			(size 0 0)
			(layers "F.Cu" "F.Mask" "F.Paste")
			(net "GND")
		)
	)
	(footprint ""
		(layer "F.Cu")
		(at 425.84878 -362.087668)
		(property "Reference" "PU71_P0_3"
			(at 8.44042 -2.23647 0)
			(unlocked yes)
			(layer "F.SilkS")
			(effects
				(font
					(size 0.7874 0.5842)
					(thickness 0.1524)
				)
				(justify left)
			)
		)
		(property "Value" ""
			(at 0 0 0)
			(layer "F.Fab")
			(effects
				(font
					(size 1.27 1.27)
				)
			)
		)
		(duplicate_pad_numbers_are_jumpers no)
		(fp_line
			(start -2.500122 -2.999994)
			(end -2.24409 -2.999994)
			(stroke
				(width 0.1524)
				(type default)
			)
			(layer "F.SilkS")
		)
		(fp_line
			(start -2.500122 -2.529078)
			(end -2.500122 -2.999994)
			(stroke
				(width 0.1524)
				(type default)
			)
			(layer "F.SilkS")
		)
		(fp_line
			(start -2.500122 0.6604)
			(end -2.500122 0.229108)
			(stroke
				(width 0.1524)
				(type default)
			)
			(layer "F.SilkS")
		)
		(fp_line
			(start -2.500122 2.999994)
			(end -2.500122 2.339594)
			(stroke
				(width 0.1524)
				(type default)
			)
			(layer "F.SilkS")
		)
		(fp_line
			(start -2.2987 2.999994)
			(end -2.500122 2.999994)
			(stroke
				(width 0.1524)
				(type default)
			)
			(layer "F.SilkS")
		)
		(fp_line
			(start 2.31394 -2.999994)
			(end 2.500122 -2.999994)
			(stroke
				(width 0.1524)
				(type default)
			)
			(layer "F.SilkS")
		)
		(fp_line
			(start 2.500122 -2.999994)
			(end 2.500122 -2.44348)
			(stroke
				(width 0.1524)
				(type default)
			)
			(layer "F.SilkS")
		)
		(fp_line
			(start 2.500122 2.339594)
			(end 2.500122 2.999994)
			(stroke
				(width 0.1524)
				(type default)
			)
			(layer "F.SilkS")
		)
		(fp_line
			(start 2.500122 2.999994)
			(end 2.2987 2.999994)
			(stroke
				(width 0.1524)
				(type default)
			)
			(layer "F.SilkS")
		)
		(fp_poly
			(pts
				(xy -2.218182 -3.583432) (xy -2.726182 -2.567432) (xy -3.234182 -3.583432)
			)
			(stroke
				(width 0)
				(type default)
			)
			(fill yes)
			(layer "F.SilkS")
		)
		(fp_line
			(start -2.500122 -2.999994)
			(end 2.500122 -2.999994)
			(stroke
				(width 0.1)
				(type default)
			)
			(layer "F.Fab")
		)
		(fp_line
			(start -2.500122 2.999994)
			(end -2.500122 -2.999994)
			(stroke
				(width 0.1)
				(type default)
			)
			(layer "F.Fab")
		)
		(fp_line
			(start 2.500122 -2.999994)
			(end 2.500122 2.999994)
			(stroke
				(width 0.1)
				(type default)
			)
			(layer "F.Fab")
		)
		(fp_line
			(start 2.500122 2.999994)
			(end -2.500122 2.999994)
			(stroke
				(width 0.1)
				(type default)
			)
			(layer "F.Fab")
		)
		(fp_poly
			(pts
				(xy -4.218432 -2.783078) (xy -4.218432 -1.767078) (xy -3.202432 -2.275078)
			)
			(stroke
				(width 0)
				(type default)
			)
			(fill yes)
			(layer "F.Fab")
		)
		(pad "1" smd rect
			(at -2.400046 -2.275078 90)
			(size 0.2286 0.6096)
			(layers "F.Cu" "F.Mask" "F.Paste")
			(net "PVCCFA_EHV_FIVRA_CPU0_VOS3")
		)
		(pad "2" smd rect
			(at -2.400046 -1.82499 90)
			(size 0.2286 0.6096)
			(layers "F.Cu" "F.Mask" "F.Paste")
			(net "GND")
		)
		(pad "3" smd rect
			(at -2.400046 -1.374902 90)
			(size 0.2286 0.6096)
			(layers "F.Cu" "F.Mask" "F.Paste")
			(net "PVCCFA_EHV_FIVRA_CPU0_VDD3")
		)
		(pad "4" smd rect
			(at -2.400046 -0.925068 90)
			(size 0.2286 0.6096)
			(layers "F.Cu" "F.Mask" "F.Paste")
			(net "PVCCFA_EHV_FIVRA_CPU0_PVCC1")
		)
		(pad "5" smd rect
			(at -2.400046 -0.47498 90)
			(size 0.2286 0.6096)
			(layers "F.Cu" "F.Mask" "F.Paste")
			(net "GND")
		)
		(pad "6" smd rect
			(at -2.400046 -0.024892 90)
			(size 0.2286 0.6096)
			(layers "F.Cu" "F.Mask" "F.Paste")
			(net "Net_8511")
		)
		(pad "7_9-20_24" smd circle
			(at 0 1.150112 90)
			(size 0 0)
			(layers "F.Cu" "F.Mask" "F.Paste")
			(net "GND")
		)
		(pad "10_19" smd rect
			(at 0 2.899918 90)
			(size 0.6096 4.318)
			(layers "F.Cu" "F.Mask" "F.Paste")
			(net "SW_PVCCFA_EHV_FIVRA_CPU0_SW3")
		)
		(pad "25_29" smd rect
			(at 1.549908 -1.279906 270)
			(size 2.0574 2.3114)
			(layers "F.Cu" "F.Mask" "F.Paste")
			(net "SW_P12V_PVCCFA_EHV_FIVRA_CPU0_R")
		)
		(pad "30" smd rect
			(at 2.05994 -2.899918)
			(size 0.2286 0.6096)
			(layers "F.Cu" "F.Mask" "F.Paste")
			(net "SW_P12V_PVCCFA_EHV_FIVRA_CPU0_R")
		)
		(pad "31" smd rect
			(at 1.610106 -2.899918)
			(size 0.2286 0.6096)
			(layers "F.Cu" "F.Mask" "F.Paste")
			(net "Net_8512")
		)
		(pad "32" smd rect
			(at 1.160018 -2.899918)
			(size 0.2286 0.6096)
			(layers "F.Cu" "F.Mask" "F.Paste")
			(net "SW_PVCCFA_EHV_FIVRA_CPU0_BOOTR3")
		)
		(pad "33" smd rect
			(at 0.70993 -2.899918)
			(size 0.2286 0.6096)
			(layers "F.Cu" "F.Mask" "F.Paste")
			(net "SW_PVCCFA_EHV_FIVRA_CPU0_BOOT3")
		)
		(pad "34" smd rect
			(at 0.260096 -2.899918)
			(size 0.2286 0.6096)
			(layers "F.Cu" "F.Mask" "F.Paste")
			(net "PVCCFA_EHV_FIVRA_CPU0_PWM3")
		)
		(pad "35" smd rect
			(at -0.189992 -2.899918)
			(size 0.2286 0.6096)
			(layers "F.Cu" "F.Mask" "F.Paste")
			(net "PVCCFA_EHV_FIVRA_CPU0_VDD3")
		)
		(pad "36" smd rect
			(at -0.64008 -2.899918)
			(size 0.2286 0.6096)
			(layers "F.Cu" "F.Mask" "F.Paste")
			(net "PVCCFA_EHV_FIVRA_CPU0_BTSEN")
		)
		(pad "37" smd rect
			(at -1.089914 -2.899918)
			(size 0.2286 0.6096)
			(layers "F.Cu" "F.Mask" "F.Paste")
			(net "PVCCFA_EHV_FIVRA_CPU0_LSET3")
		)
		(pad "38" smd rect
			(at -1.540002 -2.899918)
			(size 0.2286 0.6096)
			(layers "F.Cu" "F.Mask" "F.Paste")
			(net "PVCCFA_EHV_FIVRA_CPU0_IMON3")
		)
		(pad "39" smd rect
			(at -1.99009 -2.899918)
			(size 0.2286 0.6096)
			(layers "F.Cu" "F.Mask" "F.Paste")
			(net "PVCCIN_CPU0_VREF")
		)
		(pad "40" smd rect
			(at -0.87503 -1.27508)
			(size 1.7526 1.9558)
			(layers "F.Cu" "F.Mask" "F.Paste")
			(net "GND")
		)
		(pad "41" smd rect
			(at -1.525016 0.249936 270)
			(size 0.3048 0.4572)
			(layers "F.Cu" "F.Mask" "F.Paste")
			(net "Net_8510")
		)
		(zone
			(layer "F.Cu")
			(hatch none 0.5)
			(connect_pads
				(clearance 0)
			)
			(min_thickness 0.25)
			(keepout
				(tracks not_allowed)
				(vias allowed)
				(pads allowed)
				(copperpour not_allowed)
				(footprints allowed)
			)
			(placement
				(enabled no)
				(sheetname "")
			)
			(fill
				(thermal_gap 0.5)
				(thermal_bridge_width 0.5)
				(island_removal_mode 0)
			)
			(polygon
				(pts
					(xy 423.348658 -359.087674) (xy 423.348658 -359.836974) (xy 428.348902 -359.836974) (xy 428.348902 -359.087674)
					(xy 428.05858 -359.087674) (xy 428.05858 -359.54335) (xy 423.63898 -359.54335) (xy 423.63898 -359.087674)
				)
			)
		)
		(zone
			(layer "F.Cu")
			(hatch none 0.5)
			(connect_pads
				(clearance 0)
			)
			(min_thickness 0.25)
			(keepout
				(tracks not_allowed)
				(vias allowed)
				(pads allowed)
				(copperpour not_allowed)
				(footprints allowed)
			)
			(placement
				(enabled no)
				(sheetname "")
			)
			(fill
				(thermal_gap 0.5)
				(thermal_bridge_width 0.5)
				(island_removal_mode 0)
			)
			(polygon
				(pts
					(xy 424.07332 -362.334048) (xy 424.82262 -362.334048) (xy 424.82262 -362.016548) (xy 424.898058 -362.016548)
					(xy 424.898058 -361.385866) (xy 424.85056 -361.338368) (xy 423.348658 -361.338368) (xy 423.348658 -361.79506)
					(xy 424.044364 -361.79506) (xy 424.044364 -361.634532) (xy 424.603164 -361.634532) (xy 424.603164 -362.040932)
					(xy 424.044364 -362.040932) (xy 424.044364 -361.82046) (xy 423.348658 -361.82046) (xy 423.348658 -361.94746)
					(xy 423.804334 -361.94746) (xy 423.804334 -362.311188) (xy 424.07332 -362.311188)
				)
			)
		)
	)
	(footprint ""
		(layer "F.Cu")
		(at 164.64788 -121.376948 180)
		(property "Reference" "R1401"
			(at 0 0 180)
			(layer "F.SilkS")
			(hide yes)
			(effects
				(font
					(size 1.27 1.27)
				)
			)
		)
		(property "Value" ""
			(at 0 0 180)
			(layer "F.Fab")
			(effects
				(font
					(size 1.27 1.27)
				)
			)
		)
		(duplicate_pad_numbers_are_jumpers no)
		(fp_line
			(start 0.7874 0.4064)
			(end -0.7874 0.4064)
			(stroke
				(width 0.1524)
				(type default)
			)
			(layer "F.SilkS")
		)
		(fp_line
			(start 0.7874 -0.4064)
			(end 0.7874 0.4064)
			(stroke
				(width 0.1524)
				(type default)
			)
			(layer "F.SilkS")
		)
		(fp_line
			(start -0.7874 0.4064)
			(end -0.7874 -0.4064)
			(stroke
				(width 0.1524)
				(type default)
			)
			(layer "F.SilkS")
		)
		(fp_line
			(start -0.7874 -0.4064)
			(end 0.7874 -0.4064)
			(stroke
				(width 0.1524)
				(type default)
			)
			(layer "F.SilkS")
		)
		(fp_line
			(start 0.67945 0.3048)
			(end 0.120396 0.3048)
			(stroke
				(width 0.1)
				(type default)
			)
			(layer "F.Fab")
		)
		(fp_line
			(start 0.67945 -0.3048)
			(end 0.67945 0.3048)
			(stroke
				(width 0.1)
				(type default)
			)
			(layer "F.Fab")
		)
		(fp_line
			(start 0.12065 -0.2794)
			(end 0.12065 -0.3048)
			(stroke
				(width 0.1)
				(type default)
			)
			(layer "F.Fab")
		)
		(fp_line
			(start 0.12065 -0.3048)
			(end 0.67945 -0.3048)
			(stroke
				(width 0.1)
				(type default)
			)
			(layer "F.Fab")
		)
		(fp_line
			(start 0.120396 0.3048)
			(end 0.120396 0.2794)
			(stroke
				(width 0.1)
				(type default)
			)
			(layer "F.Fab")
		)
		(fp_line
			(start 0.120396 0.2794)
			(end -0.12065 0.2794)
			(stroke
				(width 0.1)
				(type default)
			)
			(layer "F.Fab")
		)
		(fp_line
			(start -0.12065 0.3048)
			(end -0.67945 0.3048)
			(stroke
				(width 0.1)
				(type default)
			)
			(layer "F.Fab")
		)
		(fp_line
			(start -0.12065 0.2794)
			(end -0.12065 0.3048)
			(stroke
				(width 0.1)
				(type default)
			)
			(layer "F.Fab")
		)
		(fp_line
			(start -0.12065 -0.2794)
			(end 0.12065 -0.2794)
			(stroke
				(width 0.1)
				(type default)
			)
			(layer "F.Fab")
		)
		(fp_line
			(start -0.12065 -0.305054)
			(end -0.12065 -0.2794)
			(stroke
				(width 0.1)
				(type default)
			)
			(layer "F.Fab")
		)
		(fp_line
			(start -0.67945 0.3048)
			(end -0.67945 -0.305054)
			(stroke
				(width 0.1)
				(type default)
			)
			(layer "F.Fab")
		)
		(fp_line
			(start -0.67945 -0.305054)
			(end -0.12065 -0.305054)
			(stroke
				(width 0.1)
				(type default)
			)
			(layer "F.Fab")
		)
		(pad "1" smd circle
			(at -0.40005 0 180)
			(size 0 0)
			(layers "F.Cu" "F.Mask" "F.Paste")
			(net "PU_MAIN_FPGA_CONFIG_DONE")
		)
		(pad "2" smd circle
			(at 0.40005 0 180)
			(size 0 0)
			(layers "F.Cu" "F.Mask" "F.Paste")
			(net "P3V3_AUX")
		)
	)
	(footprint ""
		(layer "F.Cu")
		(at 103.1367 -393.685268 180)
		(property "Reference" "C1963"
			(at 0 0 180)
			(layer "F.SilkS")
			(hide yes)
			(effects
				(font
					(size 1.27 1.27)
				)
			)
		)
		(property "Value" ""
			(at 0 0 180)
			(layer "F.Fab")
			(effects
				(font
					(size 1.27 1.27)
				)
			)
		)
		(duplicate_pad_numbers_are_jumpers no)
		(fp_line
			(start 0.7874 0.4064)
			(end -0.7874 0.4064)
			(stroke
				(width 0.1524)
				(type default)
			)
			(layer "F.SilkS")
		)
		(fp_line
			(start 0.7874 -0.4064)
			(end 0.7874 0.4064)
			(stroke
				(width 0.1524)
				(type default)
			)
			(layer "F.SilkS")
		)
		(fp_line
			(start -0.7874 0.4064)
			(end -0.7874 -0.4064)
			(stroke
				(width 0.1524)
				(type default)
			)
			(layer "F.SilkS")
		)
		(fp_line
			(start -0.7874 -0.4064)
			(end 0.7874 -0.4064)
			(stroke
				(width 0.1524)
				(type default)
			)
			(layer "F.SilkS")
		)
		(fp_line
			(start 0.67945 0.3048)
			(end 0.120396 0.3048)
			(stroke
				(width 0.1)
				(type default)
			)
			(layer "F.Fab")
		)
		(fp_line
			(start 0.67945 -0.3048)
			(end 0.67945 0.3048)
			(stroke
				(width 0.1)
				(type default)
			)
			(layer "F.Fab")
		)
		(fp_line
			(start 0.12065 -0.2794)
			(end 0.12065 -0.3048)
			(stroke
				(width 0.1)
				(type default)
			)
			(layer "F.Fab")
		)
		(fp_line
			(start 0.12065 -0.3048)
			(end 0.67945 -0.3048)
			(stroke
				(width 0.1)
				(type default)
			)
			(layer "F.Fab")
		)
		(fp_line
			(start 0.120396 0.3048)
			(end 0.120396 0.2794)
			(stroke
				(width 0.1)
				(type default)
			)
			(layer "F.Fab")
		)
		(fp_line
			(start 0.120396 0.2794)
			(end -0.12065 0.2794)
			(stroke
				(width 0.1)
				(type default)
			)
			(layer "F.Fab")
		)
		(fp_line
			(start -0.12065 0.3048)
			(end -0.67945 0.3048)
			(stroke
				(width 0.1)
				(type default)
			)
			(layer "F.Fab")
		)
		(fp_line
			(start -0.12065 0.2794)
			(end -0.12065 0.3048)
			(stroke
				(width 0.1)
				(type default)
			)
			(layer "F.Fab")
		)
		(fp_line
			(start -0.12065 -0.2794)
			(end 0.12065 -0.2794)
			(stroke
				(width 0.1)
				(type default)
			)
			(layer "F.Fab")
		)
		(fp_line
			(start -0.12065 -0.305054)
			(end -0.12065 -0.2794)
			(stroke
				(width 0.1)
				(type default)
			)
			(layer "F.Fab")
		)
		(fp_line
			(start -0.67945 0.3048)
			(end -0.67945 -0.305054)
			(stroke
				(width 0.1)
				(type default)
			)
			(layer "F.Fab")
		)
		(fp_line
			(start -0.67945 -0.305054)
			(end -0.12065 -0.305054)
			(stroke
				(width 0.1)
				(type default)
			)
			(layer "F.Fab")
		)
		(pad "1" smd circle
			(at -0.40005 0 180)
			(size 0 0)
			(layers "F.Cu" "F.Mask" "F.Paste")
			(net "P3V3_AUX")
		)
		(pad "2" smd circle
			(at 0.40005 0 180)
			(size 0 0)
			(layers "F.Cu" "F.Mask" "F.Paste")
			(net "GND")
		)
	)
)
